(kicad_pcb
	(version 20260206)
	(generator "pcbnew")
	(generator_version "10.0")
	(general
		(thickness 1.6)
		(legacy_teardrops no)
	)
	(paper "A4")
	(title_block
		(title "baseboard — 13948-1b.1110WZS1818.brd")
		(comment 1 "Honey Badger (Wiwynn) / footprints 1268-1274 of 2523")
	)
	(layers
		(0 "F.Cu" signal "TOP")
		(4 "In1.Cu" signal "L2GND")
		(6 "In2.Cu" signal "L3")
		(8 "In3.Cu" signal "L4VCC")
		(10 "In4.Cu" signal "L5VCC")
		(12 "In5.Cu" signal "L6")
		(14 "In6.Cu" signal "L7GND")
		(2 "B.Cu" signal "BOTTOM")
		(9 "F.Adhes" user "F.Adhesive")
		(11 "B.Adhes" user "B.Adhesive")
		(13 "F.Paste" user "Package Geometry/Pastemask Top")
		(15 "B.Paste" user "Package Geometry/Pastemask Bottom")
		(5 "F.SilkS" user "Ref Des/Silkscreen Top")
		(7 "B.SilkS" user "Ref Des/Silkscreen Bottom")
		(1 "F.Mask" user "Board Geometry/Soldermask Top")
		(3 "B.Mask" user "Board Geometry/Soldermask Bottom")
		(17 "Dwgs.User" user "User.Drawings")
		(19 "Cmts.User" user "User.Comments")
		(21 "Eco1.User" user "User.Eco1")
		(23 "Eco2.User" user "User.Eco2")
		(25 "Edge.Cuts" user "Board Geometry/Outline")
		(27 "Margin" user)
		(31 "F.CrtYd" user "Package Geometry/Place Bound Top")
		(29 "B.CrtYd" user "Package Geometry/Place Bound Bottom")
		(35 "F.Fab" user "Ref Des/Assembly Top")
		(33 "B.Fab" user "Ref Des/Assembly Bottom")
	)
	(footprint ""
		(layer "F.Cu")
		(at 201.699876 -147.184872 90)
		(property "Reference" "SR761"
			(at 0 0 90)
			(layer "F.SilkS")
			(hide yes)
			(effects
				(font
					(size 1.27 1.27)
				)
			)
		)
		(property "Value" "200KR2F-L-GP"
			(at 0.064008 -3.993896 90)
			(unlocked yes)
			(layer "F.Fab")
			(hide yes)
			(effects
				(font
					(size 1.016 1.016)
					(thickness 0.1524)
				)
			)
		)
		(property "Device Type" "R402H16"
			(at 0.064008 -5.517896 90)
			(unlocked yes)
			(layer "F.Fab")
			(hide yes)
			(effects
				(font
					(size 1.016 1.016)
					(thickness 0.1524)
				)
			)
		)
		(duplicate_pad_numbers_are_jumpers no)
		(fp_line
			(start 0.508 -0.9398)
			(end -0.508 -0.9398)
			(stroke
				(width 0.1524)
				(type default)
			)
			(layer "F.SilkS")
		)
		(fp_line
			(start -0.508 -0.9398)
			(end -0.508 0.9398)
			(stroke
				(width 0.1524)
				(type default)
			)
			(layer "F.SilkS")
		)
		(fp_rect
			(start -0.508 0.9398)
			(end 0.508 -0.9398)
			(stroke
				(width 0)
				(type default)
			)
			(fill no)
			(layer "F.CrtYd")
		)
		(fp_rect
			(start -0.508 0.9398)
			(end 0.508 -0.9398)
			(stroke
				(width 0)
				(type default)
			)
			(fill no)
			(layer "F.Fab")
		)
		(pad "1" smd custom
			(at 0 -0.4445 90)
			(size 0.1397 0.1397)
			(layers "F.Cu" "F.Mask" "F.Paste")
			(net "EXP_I2C_VREF_2")
			(options
				(clearance outline)
				(anchor circle)
			)
			(primitives
				(gr_poly
					(pts
						(arc
							(start -0.1778 -0.2794)
							(mid -0.249642 -0.249642)
							(end -0.2794 -0.1778)
						)
						(arc
							(start -0.2794 0.1778)
							(mid -0.249642 0.249642)
							(end -0.1778 0.2794)
						)
						(arc
							(start 0.1778 0.2794)
							(mid 0.249642 0.249642)
							(end 0.2794 0.1778)
						)
						(arc
							(start 0.2794 -0.1778)
							(mid 0.249642 -0.249642)
							(end 0.1778 -0.2794)
						)
					)
					(width 0)
					(fill yes)
				)
			)
		)
		(pad "2" smd custom
			(at 0 0.4445 90)
			(size 0.1397 0.1397)
			(layers "F.Cu" "F.Mask" "F.Paste")
			(net "P3V3_STBY")
			(options
				(clearance outline)
				(anchor circle)
			)
			(primitives
				(gr_poly
					(pts
						(arc
							(start -0.1778 -0.2794)
							(mid -0.249642 -0.249642)
							(end -0.2794 -0.1778)
						)
						(arc
							(start -0.2794 0.1778)
							(mid -0.249642 0.249642)
							(end -0.1778 0.2794)
						)
						(arc
							(start 0.1778 0.2794)
							(mid 0.249642 0.249642)
							(end 0.2794 0.1778)
						)
						(arc
							(start 0.2794 -0.1778)
							(mid 0.249642 -0.249642)
							(end 0.1778 -0.2794)
						)
					)
					(width 0)
					(fill yes)
				)
			)
		)
	)
	(footprint ""
		(layer "F.Cu")
		(at 121.93397 -114.3 180)
		(property "Reference" "SC1068"
			(at 0 0 180)
			(layer "F.SilkS")
			(hide yes)
			(effects
				(font
					(size 1.27 1.27)
				)
			)
		)
		(property "Value" "SCD01U10V1KX-GP"
			(at -2.8321 -1.7399 180)
			(unlocked yes)
			(layer "F.Fab")
			(hide yes)
			(effects
				(font
					(size 1.016 1.016)
					(thickness 0.1524)
				)
			)
		)
		(property "Device Type" "C0201H13"
			(at -2.8321 -3.2639 180)
			(unlocked yes)
			(layer "F.Fab")
			(hide yes)
			(effects
				(font
					(size 1.016 1.016)
					(thickness 0.1524)
				)
			)
		)
		(duplicate_pad_numbers_are_jumpers no)
		(fp_rect
			(start -0.2794 0.6477)
			(end 0.2794 -0.6477)
			(stroke
				(width 0)
				(type default)
			)
			(fill no)
			(layer "F.CrtYd")
		)
		(fp_rect
			(start -0.2794 0.6477)
			(end 0.2794 -0.6477)
			(stroke
				(width 0)
				(type default)
			)
			(fill no)
			(layer "F.Fab")
		)
		(pad "1" smd custom
			(at 0 -0.2794 180)
			(size 0.0762 0.0762)
			(layers "F.Cu" "F.Mask" "F.Paste")
			(net "SAS_HDD_TX0_P")
			(options
				(clearance outline)
				(anchor circle)
			)
			(primitives
				(gr_poly
					(pts
						(arc
							(start 0.1524 -0.127)
							(mid 0.137521 -0.162921)
							(end 0.1016 -0.1778)
						)
						(arc
							(start -0.1016 -0.1778)
							(mid -0.137521 -0.162921)
							(end -0.1524 -0.127)
						)
						(arc
							(start -0.1524 0.127)
							(mid -0.137521 0.162921)
							(end -0.1016 0.1778)
						)
						(arc
							(start 0.1016 0.1778)
							(mid 0.137521 0.162921)
							(end 0.1524 0.127)
						)
					)
					(width 0)
					(fill yes)
				)
			)
		)
		(pad "2" smd custom
			(at 0 0.2794 180)
			(size 0.0762 0.0762)
			(layers "F.Cu" "F.Mask" "F.Paste")
			(net "SAS_EXP_GF_TX_DP4")
			(options
				(clearance outline)
				(anchor circle)
			)
			(primitives
				(gr_poly
					(pts
						(arc
							(start 0.1524 -0.127)
							(mid 0.137521 -0.162921)
							(end 0.1016 -0.1778)
						)
						(arc
							(start -0.1016 -0.1778)
							(mid -0.137521 -0.162921)
							(end -0.1524 -0.127)
						)
						(arc
							(start -0.1524 0.127)
							(mid -0.137521 0.162921)
							(end -0.1016 0.1778)
						)
						(arc
							(start 0.1016 0.1778)
							(mid 0.137521 0.162921)
							(end 0.1524 0.127)
						)
					)
					(width 0)
					(fill yes)
				)
			)
		)
	)
	(footprint ""
		(layer "F.Cu")
		(at 280.289 -198.247 -90)
		(property "Reference" "C194"
			(at 0 0 270)
			(layer "F.SilkS")
			(hide yes)
			(effects
				(font
					(size 1.27 1.27)
				)
			)
		)
		(property "Value" "SC1U6D3V3KX-2GP"
			(at 0 -2.8194 270)
			(unlocked yes)
			(layer "F.Fab")
			(hide yes)
			(effects
				(font
					(size 1.016 1.016)
					(thickness 0.1524)
				)
			)
		)
		(property "Device Type" "C603H36"
			(at 0 -4.3434 270)
			(unlocked yes)
			(layer "F.Fab")
			(hide yes)
			(effects
				(font
					(size 1.016 1.016)
					(thickness 0.1524)
				)
			)
		)
		(duplicate_pad_numbers_are_jumpers no)
		(fp_line
			(start 0.508 0)
			(end -0.508 0)
			(stroke
				(width 0.2032)
				(type default)
			)
			(layer "F.SilkS")
		)
		(fp_rect
			(start -0.5842 1.3335)
			(end 0.5842 -1.3335)
			(stroke
				(width 0)
				(type default)
			)
			(fill no)
			(layer "F.CrtYd")
		)
		(fp_rect
			(start -0.5842 1.3335)
			(end 0.5842 -1.3335)
			(stroke
				(width 0)
				(type default)
			)
			(fill no)
			(layer "F.Fab")
		)
		(pad "1" smd custom
			(at 0 -0.762 270)
			(size 0.2159 0.2159)
			(layers "F.Cu" "F.Mask" "F.Paste")
			(net "MPLLAV33")
			(options
				(clearance outline)
				(anchor circle)
			)
			(primitives
				(gr_poly
					(pts
						(arc
							(start -0.3302 -0.4318)
							(mid -0.402042 -0.402042)
							(end -0.4318 -0.3302)
						)
						(arc
							(start -0.4318 0.3302)
							(mid -0.402042 0.402042)
							(end -0.3302 0.4318)
						)
						(arc
							(start 0.3302 0.4318)
							(mid 0.402042 0.402042)
							(end 0.4318 0.3302)
						)
						(arc
							(start 0.4318 -0.3302)
							(mid 0.402042 -0.402042)
							(end 0.3302 -0.4318)
						)
					)
					(width 0)
					(fill yes)
				)
			)
		)
		(pad "2" smd custom
			(at 0 0.762 270)
			(size 0.2159 0.2159)
			(layers "F.Cu" "F.Mask" "F.Paste")
			(net "GND")
			(options
				(clearance outline)
				(anchor circle)
			)
			(primitives
				(gr_poly
					(pts
						(arc
							(start -0.3302 -0.4318)
							(mid -0.402042 -0.402042)
							(end -0.4318 -0.3302)
						)
						(arc
							(start -0.4318 0.3302)
							(mid -0.402042 0.402042)
							(end -0.3302 0.4318)
						)
						(arc
							(start 0.3302 0.4318)
							(mid 0.402042 0.402042)
							(end 0.4318 0.3302)
						)
						(arc
							(start 0.4318 -0.3302)
							(mid 0.402042 -0.402042)
							(end 0.3302 -0.4318)
						)
					)
					(width 0)
					(fill yes)
				)
			)
		)
	)
	(footprint ""
		(layer "F.Cu")
		(at 194.183 -34.036 -90)
		(property "Reference" "R463"
			(at 0 0 270)
			(layer "F.SilkS")
			(hide yes)
			(effects
				(font
					(size 1.27 1.27)
				)
			)
		)
		(property "Value" "0R2J-2-GP"
			(at 0.064008 -3.993896 270)
			(unlocked yes)
			(layer "F.Fab")
			(hide yes)
			(effects
				(font
					(size 1.016 1.016)
					(thickness 0.1524)
				)
			)
		)
		(property "Device Type" "R402H16"
			(at 0.064008 -5.517896 270)
			(unlocked yes)
			(layer "F.Fab")
			(hide yes)
			(effects
				(font
					(size 1.016 1.016)
					(thickness 0.1524)
				)
			)
		)
		(duplicate_pad_numbers_are_jumpers no)
		(fp_line
			(start -0.508 -0.9398)
			(end -0.508 0.9398)
			(stroke
				(width 0.1524)
				(type default)
			)
			(layer "F.SilkS")
		)
		(fp_line
			(start 0.508 -0.9398)
			(end -0.508 -0.9398)
			(stroke
				(width 0.1524)
				(type default)
			)
			(layer "F.SilkS")
		)
		(fp_rect
			(start -0.508 0.9398)
			(end 0.508 -0.9398)
			(stroke
				(width 0)
				(type default)
			)
			(fill no)
			(layer "F.CrtYd")
		)
		(fp_rect
			(start -0.508 0.9398)
			(end 0.508 -0.9398)
			(stroke
				(width 0)
				(type default)
			)
			(fill no)
			(layer "F.Fab")
		)
		(pad "1" smd custom
			(at 0 -0.4445 270)
			(size 0.1397 0.1397)
			(layers "F.Cu" "F.Mask" "F.Paste")
			(net "GND")
			(options
				(clearance outline)
				(anchor circle)
			)
			(primitives
				(gr_poly
					(pts
						(arc
							(start -0.1778 -0.2794)
							(mid -0.249642 -0.249642)
							(end -0.2794 -0.1778)
						)
						(arc
							(start -0.2794 0.1778)
							(mid -0.249642 0.249642)
							(end -0.1778 0.2794)
						)
						(arc
							(start 0.1778 0.2794)
							(mid 0.249642 0.249642)
							(end 0.2794 0.1778)
						)
						(arc
							(start 0.2794 -0.1778)
							(mid 0.249642 -0.249642)
							(end 0.1778 -0.2794)
						)
					)
					(width 0)
					(fill yes)
				)
			)
		)
		(pad "2" smd custom
			(at 0 0.4445 270)
			(size 0.1397 0.1397)
			(layers "F.Cu" "F.Mask" "F.Paste")
			(net "RMII_BMC_TX_EN")
			(options
				(clearance outline)
				(anchor circle)
			)
			(primitives
				(gr_poly
					(pts
						(arc
							(start -0.1778 -0.2794)
							(mid -0.249642 -0.249642)
							(end -0.2794 -0.1778)
						)
						(arc
							(start -0.2794 0.1778)
							(mid -0.249642 0.249642)
							(end -0.1778 0.2794)
						)
						(arc
							(start 0.1778 0.2794)
							(mid 0.249642 0.249642)
							(end 0.2794 0.1778)
						)
						(arc
							(start 0.2794 -0.1778)
							(mid 0.249642 -0.249642)
							(end 0.1778 -0.2794)
						)
					)
					(width 0)
					(fill yes)
				)
			)
		)
	)
	(footprint ""
		(layer "F.Cu")
		(at 48.768 -214.376 -90)
		(property "Reference" "R2103"
			(at 0 0 270)
			(layer "F.SilkS")
			(hide yes)
			(effects
				(font
					(size 1.27 1.27)
				)
			)
		)
		(property "Value" "150KR2J-GP"
			(at 0.064008 -3.993896 270)
			(unlocked yes)
			(layer "F.Fab")
			(hide yes)
			(effects
				(font
					(size 1.016 1.016)
					(thickness 0.1524)
				)
			)
		)
		(property "Device Type" "R402H16"
			(at 0.064008 -5.517896 270)
			(unlocked yes)
			(layer "F.Fab")
			(hide yes)
			(effects
				(font
					(size 1.016 1.016)
					(thickness 0.1524)
				)
			)
		)
		(duplicate_pad_numbers_are_jumpers no)
		(fp_line
			(start -0.508 -0.9398)
			(end -0.508 0.9398)
			(stroke
				(width 0.1524)
				(type default)
			)
			(layer "F.SilkS")
		)
		(fp_line
			(start 0.508 -0.9398)
			(end -0.508 -0.9398)
			(stroke
				(width 0.1524)
				(type default)
			)
			(layer "F.SilkS")
		)
		(fp_rect
			(start -0.508 0.9398)
			(end 0.508 -0.9398)
			(stroke
				(width 0)
				(type default)
			)
			(fill no)
			(layer "F.CrtYd")
		)
		(fp_rect
			(start -0.508 0.9398)
			(end 0.508 -0.9398)
			(stroke
				(width 0)
				(type default)
			)
			(fill no)
			(layer "F.Fab")
		)
		(pad "1" smd custom
			(at 0 -0.4445 270)
			(size 0.1397 0.1397)
			(layers "F.Cu" "F.Mask" "F.Paste")
			(net "MB0_CM_ADR1_R")
			(options
				(clearance outline)
				(anchor circle)
			)
			(primitives
				(gr_poly
					(pts
						(arc
							(start -0.1778 -0.2794)
							(mid -0.249642 -0.249642)
							(end -0.2794 -0.1778)
						)
						(arc
							(start -0.2794 0.1778)
							(mid -0.249642 0.249642)
							(end -0.1778 0.2794)
						)
						(arc
							(start 0.1778 0.2794)
							(mid 0.249642 0.249642)
							(end 0.2794 0.1778)
						)
						(arc
							(start 0.2794 -0.1778)
							(mid 0.249642 -0.249642)
							(end 0.1778 -0.2794)
						)
					)
					(width 0)
					(fill yes)
				)
			)
		)
		(pad "2" smd custom
			(at 0 0.4445 270)
			(size 0.1397 0.1397)
			(layers "F.Cu" "F.Mask" "F.Paste")
			(net "AGND_CURRENT_MON")
			(options
				(clearance outline)
				(anchor circle)
			)
			(primitives
				(gr_poly
					(pts
						(arc
							(start -0.1778 -0.2794)
							(mid -0.249642 -0.249642)
							(end -0.2794 -0.1778)
						)
						(arc
							(start -0.2794 0.1778)
							(mid -0.249642 0.249642)
							(end -0.1778 0.2794)
						)
						(arc
							(start 0.1778 0.2794)
							(mid 0.249642 0.249642)
							(end 0.2794 0.1778)
						)
						(arc
							(start 0.2794 -0.1778)
							(mid 0.249642 -0.249642)
							(end 0.1778 -0.2794)
						)
					)
					(width 0)
					(fill yes)
				)
			)
		)
	)
	(footprint ""
		(layer "F.Cu")
		(at 258.318 -16.383 180)
		(property "Reference" "F1"
			(at 0 0 180)
			(layer "F.SilkS")
			(hide yes)
			(effects
				(font
					(size 1.27 1.27)
				)
			)
		)
		(property "Value" "POLYSW-1D5A8V-4-GP"
			(at -2.401824 -0.181102 180)
			(unlocked yes)
			(layer "F.Fab")
			(hide yes)
			(effects
				(font
					(size 1.016 1.016)
					(thickness 0.1524)
				)
			)
		)
		(property "Device Type" "POLYSW-3217-UH40"
			(at -2.401824 -1.705102 180)
			(unlocked yes)
			(layer "F.Fab")
			(hide yes)
			(effects
				(font
					(size 1.016 1.016)
					(thickness 0.1524)
				)
			)
		)
		(duplicate_pad_numbers_are_jumpers no)
		(fp_line
			(start 1.2065 2.2479)
			(end 1.2065 -2.2479)
			(stroke
				(width 0.1524)
				(type default)
			)
			(layer "F.SilkS")
		)
		(fp_line
			(start 1.2065 -2.2479)
			(end -1.2065 -2.2479)
			(stroke
				(width 0.1524)
				(type default)
			)
			(layer "F.SilkS")
		)
		(fp_line
			(start -1.2065 2.2479)
			(end 1.2065 2.2479)
			(stroke
				(width 0.1524)
				(type default)
			)
			(layer "F.SilkS")
		)
		(fp_line
			(start -1.2065 -2.2479)
			(end -1.2065 2.2479)
			(stroke
				(width 0.1524)
				(type default)
			)
			(layer "F.SilkS")
		)
		(fp_rect
			(start -0.8255 1.6002)
			(end 0.8255 -1.6002)
			(stroke
				(width 0)
				(type default)
			)
			(fill no)
			(layer "F.CrtYd")
		)
		(fp_poly
			(pts
				(xy -1.4605 2.3241) (xy -1.4605 -2.3241) (xy 1.4605 -2.3241) (xy 1.4605 1.59512) (xy 0.8255 1.59512)
				(xy 0.8255 -1.6002) (xy -0.8255 -1.6002) (xy -0.8255 1.6002) (xy 1.4605 1.6002) (xy 1.4605 2.3241)
			)
			(stroke
				(width 0)
				(type default)
			)
			(fill no)
			(layer "F.CrtYd")
		)
		(fp_rect
			(start -1.4605 2.3241)
			(end 1.4605 -2.3241)
			(stroke
				(width 0)
				(type default)
			)
			(fill no)
			(layer "F.Fab")
		)
		(pad "1" smd rect
			(at 0 -1.417574 180)
			(size 1.905 1.143)
			(layers "F.Cu" "F.Mask" "F.Paste")
			(net "P5V_USB")
		)
		(pad "2" smd rect
			(at 0 1.417574 180)
			(size 1.905 1.143)
			(layers "F.Cu" "F.Mask" "F.Paste")
			(net "P5V_USB_BP1_F")
		)
	)
	(footprint ""
		(layer "F.Cu")
		(at 181.36997 -67.183)
		(property "Reference" "C290"
			(at 0 0 0)
			(layer "F.SilkS")
			(hide yes)
			(effects
				(font
					(size 1.27 1.27)
				)
			)
		)
		(property "Value" "SCD1U25V2KX-2-GP"
			(at 1.1811 -2.7051 0)
			(unlocked yes)
			(layer "F.Fab")
			(hide yes)
			(effects
				(font
					(size 1.016 1.016)
					(thickness 0.1524)
				)
			)
		)
		(property "Device Type" "C402H22"
			(at 1.1811 -4.2291 0)
			(unlocked yes)
			(layer "F.Fab")
			(hide yes)
			(effects
				(font
					(size 1.016 1.016)
					(thickness 0.1524)
				)
			)
		)
		(duplicate_pad_numbers_are_jumpers no)
		(fp_rect
			(start -0.4318 0.9525)
			(end 0.4318 -0.9525)
			(stroke
				(width 0)
				(type default)
			)
			(fill no)
			(layer "F.CrtYd")
		)
		(fp_rect
			(start -0.4318 0.9525)
			(end 0.4318 -0.9525)
			(stroke
				(width 0)
				(type default)
			)
			(fill no)
			(layer "F.Fab")
		)
		(pad "1" smd custom
			(at 0 -0.4445)
			(size 0.1524 0.1524)
			(layers "F.Cu" "F.Mask" "F.Paste")
			(net "TP_MSB_A33_CPU_SATA_RX_P")
			(options
				(clearance outline)
				(anchor circle)
			)
			(primitives
				(gr_poly
					(pts
						(arc
							(start 0.3048 -0.2032)
							(mid 0.275042 -0.275042)
							(end 0.2032 -0.3048)
						)
						(arc
							(start -0.2032 -0.3048)
							(mid -0.275042 -0.275042)
							(end -0.3048 -0.2032)
						)
						(arc
							(start -0.3048 0.2032)
							(mid -0.275042 0.275042)
							(end -0.2032 0.3048)
						)
						(arc
							(start 0.2032 0.3048)
							(mid 0.275042 0.275042)
							(end 0.3048 0.2032)
						)
					)
					(width 0)
					(fill yes)
				)
			)
		)
		(pad "2" smd custom
			(at 0 0.4445)
			(size 0.1524 0.1524)
			(layers "F.Cu" "F.Mask" "F.Paste")
			(net "GND")
			(options
				(clearance outline)
				(anchor circle)
			)
			(primitives
				(gr_poly
					(pts
						(arc
							(start 0.3048 -0.2032)
							(mid 0.275042 -0.275042)
							(end 0.2032 -0.3048)
						)
						(arc
							(start -0.2032 -0.3048)
							(mid -0.275042 -0.275042)
							(end -0.3048 -0.2032)
						)
						(arc
							(start -0.3048 0.2032)
							(mid -0.275042 0.275042)
							(end -0.2032 0.3048)
						)
						(arc
							(start 0.2032 0.3048)
							(mid 0.275042 0.275042)
							(end 0.3048 0.2032)
						)
					)
					(width 0)
					(fill yes)
				)
			)
		)
	)
)
